(kicad_pcb
	(version 20260206)
	(generator "pcbnew")
	(generator_version "10.0")
	(general
		(thickness 1.6)
		(legacy_teardrops no)
	)
	(paper "A4")
	(title_block
		(title "01162023_DA0F0TEBIF0_F0T_Expander_BD_F_brd_V02_OCP.brd")
		(comment 1 "Grand Teton / footprints 2376-2382 of 9728")
	)
	(layers
		(0 "F.Cu" signal "TOP")
		(4 "In1.Cu" signal "GND")
		(6 "In2.Cu" signal "VCC")
		(8 "In3.Cu" signal "VCC1")
		(10 "In4.Cu" signal "GND1")
		(12 "In5.Cu" signal "IN1")
		(14 "In6.Cu" signal "GND2")
		(16 "In7.Cu" signal "IN2")
		(18 "In8.Cu" signal "GND3")
		(20 "In9.Cu" signal "IN3")
		(22 "In10.Cu" signal "GND4")
		(24 "In11.Cu" signal "IN4")
		(26 "In12.Cu" signal "GND5")
		(28 "In13.Cu" signal "IN5")
		(30 "In14.Cu" signal "GND6")
		(32 "In15.Cu" signal "IN6")
		(34 "In16.Cu" signal "GND7")
		(2 "B.Cu" signal "BOTTOM")
		(9 "F.Adhes" user "F.Adhesive")
		(11 "B.Adhes" user "B.Adhesive")
		(13 "F.Paste" user "Package Geometry/Pastemask Top")
		(15 "B.Paste" user "Package Geometry/Pastemask Bottom")
		(5 "F.SilkS" user "Ref Des/Silkscreen Top")
		(7 "B.SilkS" user "Ref Des/Silkscreen Bottom")
		(1 "F.Mask" user "Board Geometry/Soldermask Top")
		(3 "B.Mask" user "Board Geometry/Soldermask Bottom")
		(17 "Dwgs.User" user "User.Drawings")
		(19 "Cmts.User" user "User.Comments")
		(21 "Eco1.User" user "User.Eco1")
		(23 "Eco2.User" user "User.Eco2")
		(25 "Edge.Cuts" user "Board Geometry/Outline")
		(27 "Margin" user)
		(31 "F.CrtYd" user "Package Geometry/Place Bound Top")
		(29 "B.CrtYd" user "Package Geometry/Place Bound Bottom")
		(35 "F.Fab" user "Ref Des/Assembly Top")
		(33 "B.Fab" user "Ref Des/Assembly Bottom")
	)
	(footprint ""
		(layer "F.Cu")
		(at 358.369362 -118.343426 90)
		(property "Reference" "R6046"
			(at 0 0 90)
			(layer "F.SilkS")
			(hide yes)
			(effects
				(font
					(size 1.27 1.27)
				)
			)
		)
		(property "Value" ""
			(at 0 0 90)
			(layer "F.Fab")
			(effects
				(font
					(size 1.27 1.27)
				)
			)
		)
		(duplicate_pad_numbers_are_jumpers no)
		(fp_line
			(start 0.7874 -0.4064)
			(end 0.7874 0.4064)
			(stroke
				(width 0.1524)
				(type default)
			)
			(layer "F.SilkS")
		)
		(fp_line
			(start -0.7874 -0.4064)
			(end 0.7874 -0.4064)
			(stroke
				(width 0.1524)
				(type default)
			)
			(layer "F.SilkS")
		)
		(fp_line
			(start 0.7874 0.4064)
			(end -0.7874 0.4064)
			(stroke
				(width 0.1524)
				(type default)
			)
			(layer "F.SilkS")
		)
		(fp_line
			(start -0.7874 0.4064)
			(end -0.7874 -0.4064)
			(stroke
				(width 0.1524)
				(type default)
			)
			(layer "F.SilkS")
		)
		(fp_line
			(start -0.12065 -0.305054)
			(end -0.12065 -0.2794)
			(stroke
				(width 0.1)
				(type default)
			)
			(layer "F.Fab")
		)
		(fp_line
			(start -0.67945 -0.305054)
			(end -0.12065 -0.305054)
			(stroke
				(width 0.1)
				(type default)
			)
			(layer "F.Fab")
		)
		(fp_line
			(start 0.67945 -0.3048)
			(end 0.67945 0.3048)
			(stroke
				(width 0.1)
				(type default)
			)
			(layer "F.Fab")
		)
		(fp_line
			(start 0.12065 -0.3048)
			(end 0.67945 -0.3048)
			(stroke
				(width 0.1)
				(type default)
			)
			(layer "F.Fab")
		)
		(fp_line
			(start 0.12065 -0.2794)
			(end 0.12065 -0.3048)
			(stroke
				(width 0.1)
				(type default)
			)
			(layer "F.Fab")
		)
		(fp_line
			(start -0.12065 -0.2794)
			(end 0.12065 -0.2794)
			(stroke
				(width 0.1)
				(type default)
			)
			(layer "F.Fab")
		)
		(fp_line
			(start 0.120396 0.2794)
			(end -0.12065 0.2794)
			(stroke
				(width 0.1)
				(type default)
			)
			(layer "F.Fab")
		)
		(fp_line
			(start -0.12065 0.2794)
			(end -0.12065 0.3048)
			(stroke
				(width 0.1)
				(type default)
			)
			(layer "F.Fab")
		)
		(fp_line
			(start 0.67945 0.3048)
			(end 0.120396 0.3048)
			(stroke
				(width 0.1)
				(type default)
			)
			(layer "F.Fab")
		)
		(fp_line
			(start 0.120396 0.3048)
			(end 0.120396 0.2794)
			(stroke
				(width 0.1)
				(type default)
			)
			(layer "F.Fab")
		)
		(fp_line
			(start -0.12065 0.3048)
			(end -0.67945 0.3048)
			(stroke
				(width 0.1)
				(type default)
			)
			(layer "F.Fab")
		)
		(fp_line
			(start -0.67945 0.3048)
			(end -0.67945 -0.305054)
			(stroke
				(width 0.1)
				(type default)
			)
			(layer "F.Fab")
		)
		(pad "1" smd circle
			(at -0.40005 0 90)
			(size 0 0)
			(layers "F.Cu" "F.Mask" "F.Paste")
			(net "PWRGD_P3V3_NIC6_D")
		)
		(pad "2" smd circle
			(at 0.40005 0 90)
			(size 0 0)
			(layers "F.Cu" "F.Mask" "F.Paste")
			(net "PWRGD_P3V3_NIC6_R")
		)
	)
	(footprint ""
		(layer "F.Cu")
		(at 110.038896 -393.740132)
		(property "Reference" "C3635"
			(at 0 0 0)
			(layer "F.SilkS")
			(hide yes)
			(effects
				(font
					(size 1.27 1.27)
				)
			)
		)
		(property "Value" ""
			(at 0 0 0)
			(layer "F.Fab")
			(effects
				(font
					(size 1.27 1.27)
				)
			)
		)
		(duplicate_pad_numbers_are_jumpers no)
		(fp_line
			(start -0.7874 -0.4064)
			(end 0.7874 -0.4064)
			(stroke
				(width 0.1524)
				(type default)
			)
			(layer "F.SilkS")
		)
		(fp_line
			(start -0.7874 0.4064)
			(end -0.7874 -0.4064)
			(stroke
				(width 0.1524)
				(type default)
			)
			(layer "F.SilkS")
		)
		(fp_line
			(start 0.7874 -0.4064)
			(end 0.7874 0.4064)
			(stroke
				(width 0.1524)
				(type default)
			)
			(layer "F.SilkS")
		)
		(fp_line
			(start 0.7874 0.4064)
			(end -0.7874 0.4064)
			(stroke
				(width 0.1524)
				(type default)
			)
			(layer "F.SilkS")
		)
		(fp_line
			(start -0.67945 -0.305054)
			(end -0.12065 -0.305054)
			(stroke
				(width 0.1)
				(type default)
			)
			(layer "F.Fab")
		)
		(fp_line
			(start -0.67945 0.3048)
			(end -0.67945 -0.305054)
			(stroke
				(width 0.1)
				(type default)
			)
			(layer "F.Fab")
		)
		(fp_line
			(start -0.12065 -0.305054)
			(end -0.12065 -0.2794)
			(stroke
				(width 0.1)
				(type default)
			)
			(layer "F.Fab")
		)
		(fp_line
			(start -0.12065 -0.2794)
			(end 0.12065 -0.2794)
			(stroke
				(width 0.1)
				(type default)
			)
			(layer "F.Fab")
		)
		(fp_line
			(start -0.12065 0.2794)
			(end -0.12065 0.3048)
			(stroke
				(width 0.1)
				(type default)
			)
			(layer "F.Fab")
		)
		(fp_line
			(start -0.12065 0.3048)
			(end -0.67945 0.3048)
			(stroke
				(width 0.1)
				(type default)
			)
			(layer "F.Fab")
		)
		(fp_line
			(start 0.120396 0.2794)
			(end -0.12065 0.2794)
			(stroke
				(width 0.1)
				(type default)
			)
			(layer "F.Fab")
		)
		(fp_line
			(start 0.120396 0.3048)
			(end 0.120396 0.2794)
			(stroke
				(width 0.1)
				(type default)
			)
			(layer "F.Fab")
		)
		(fp_line
			(start 0.12065 -0.3048)
			(end 0.67945 -0.3048)
			(stroke
				(width 0.1)
				(type default)
			)
			(layer "F.Fab")
		)
		(fp_line
			(start 0.12065 -0.2794)
			(end 0.12065 -0.3048)
			(stroke
				(width 0.1)
				(type default)
			)
			(layer "F.Fab")
		)
		(fp_line
			(start 0.67945 -0.3048)
			(end 0.67945 0.3048)
			(stroke
				(width 0.1)
				(type default)
			)
			(layer "F.Fab")
		)
		(fp_line
			(start 0.67945 0.3048)
			(end 0.120396 0.3048)
			(stroke
				(width 0.1)
				(type default)
			)
			(layer "F.Fab")
		)
		(pad "1" smd circle
			(at -0.40005 0)
			(size 0 0)
			(layers "F.Cu" "F.Mask" "F.Paste")
			(net "BIC_USB_HUB_XIN")
		)
		(pad "2" smd circle
			(at 0.40005 0)
			(size 0 0)
			(layers "F.Cu" "F.Mask" "F.Paste")
			(net "GND")
		)
	)
	(footprint ""
		(layer "F.Cu")
		(at 368.450114 -276.010116)
		(property "Reference" "H139"
			(at -0.739394 -4.636516 0)
			(unlocked yes)
			(layer "F.SilkS")
			(effects
				(font
					(size 0.7874 0.5842)
					(thickness 0.1524)
				)
				(justify left)
			)
		)
		(property "Value" ""
			(at 0 0 0)
			(layer "F.Fab")
			(effects
				(font
					(size 1.27 1.27)
				)
			)
		)
		(duplicate_pad_numbers_are_jumpers no)
		(pad "1" thru_hole circle
			(at 0 0)
			(size 6.5024 6.5024)
			(drill 3.2004)
			(layers "*.Cu" "*.Mask")
			(remove_unused_layers no)
			(net "GND")
			(clearance -1.397)
		)
	)
	(footprint ""
		(layer "F.Cu")
		(at 190.141352 -343.952322 90)
		(property "Reference" "C2538"
			(at 0 0 90)
			(layer "F.SilkS")
			(hide yes)
			(effects
				(font
					(size 1.27 1.27)
				)
			)
		)
		(property "Value" ""
			(at 0 0 90)
			(layer "F.Fab")
			(effects
				(font
					(size 1.27 1.27)
				)
			)
		)
		(duplicate_pad_numbers_are_jumpers no)
		(fp_line
			(start 0.299974 -0.150114)
			(end 0.299974 0.150114)
			(stroke
				(width 0.1)
				(type default)
			)
			(layer "F.Fab")
		)
		(fp_line
			(start -0.299974 -0.150114)
			(end 0.299974 -0.150114)
			(stroke
				(width 0.1)
				(type default)
			)
			(layer "F.Fab")
		)
		(fp_line
			(start 0.299974 0.150114)
			(end -0.299974 0.150114)
			(stroke
				(width 0.1)
				(type default)
			)
			(layer "F.Fab")
		)
		(fp_line
			(start -0.299974 0.150114)
			(end -0.299974 -0.150114)
			(stroke
				(width 0.1)
				(type default)
			)
			(layer "F.Fab")
		)
		(pad "1" smd rect
			(at -0.2667 0 90)
			(size 0.3048 0.381)
			(layers "F.Cu" "F.Mask" "F.Paste")
			(net "P5E_PEX1_STN4_TX_DP<66>")
		)
		(pad "2" smd rect
			(at 0.2667 0 90)
			(size 0.3048 0.381)
			(layers "F.Cu" "F.Mask" "F.Paste")
			(net "P5E_PEX1_STN4_TX_C_DP<66>")
		)
	)
	(footprint ""
		(layer "F.Cu")
		(at 240.54816 -55.81142 -90)
		(property "Reference" "R894"
			(at 0 0 270)
			(layer "F.SilkS")
			(hide yes)
			(effects
				(font
					(size 1.27 1.27)
				)
			)
		)
		(property "Value" ""
			(at 0 0 270)
			(layer "F.Fab")
			(effects
				(font
					(size 1.27 1.27)
				)
			)
		)
		(duplicate_pad_numbers_are_jumpers no)
		(fp_line
			(start -0.7874 0.4064)
			(end -0.7874 -0.4064)
			(stroke
				(width 0.1524)
				(type default)
			)
			(layer "F.SilkS")
		)
		(fp_line
			(start 0.7874 0.4064)
			(end -0.7874 0.4064)
			(stroke
				(width 0.1524)
				(type default)
			)
			(layer "F.SilkS")
		)
		(fp_line
			(start -0.7874 -0.4064)
			(end 0.7874 -0.4064)
			(stroke
				(width 0.1524)
				(type default)
			)
			(layer "F.SilkS")
		)
		(fp_line
			(start 0.7874 -0.4064)
			(end 0.7874 0.4064)
			(stroke
				(width 0.1524)
				(type default)
			)
			(layer "F.SilkS")
		)
		(fp_line
			(start -0.67945 0.3048)
			(end -0.67945 -0.305054)
			(stroke
				(width 0.1)
				(type default)
			)
			(layer "F.Fab")
		)
		(fp_line
			(start -0.12065 0.3048)
			(end -0.67945 0.3048)
			(stroke
				(width 0.1)
				(type default)
			)
			(layer "F.Fab")
		)
		(fp_line
			(start 0.120396 0.3048)
			(end 0.120396 0.2794)
			(stroke
				(width 0.1)
				(type default)
			)
			(layer "F.Fab")
		)
		(fp_line
			(start 0.67945 0.3048)
			(end 0.120396 0.3048)
			(stroke
				(width 0.1)
				(type default)
			)
			(layer "F.Fab")
		)
		(fp_line
			(start -0.12065 0.2794)
			(end -0.12065 0.3048)
			(stroke
				(width 0.1)
				(type default)
			)
			(layer "F.Fab")
		)
		(fp_line
			(start 0.120396 0.2794)
			(end -0.12065 0.2794)
			(stroke
				(width 0.1)
				(type default)
			)
			(layer "F.Fab")
		)
		(fp_line
			(start -0.12065 -0.2794)
			(end 0.12065 -0.2794)
			(stroke
				(width 0.1)
				(type default)
			)
			(layer "F.Fab")
		)
		(fp_line
			(start 0.12065 -0.2794)
			(end 0.12065 -0.3048)
			(stroke
				(width 0.1)
				(type default)
			)
			(layer "F.Fab")
		)
		(fp_line
			(start 0.12065 -0.3048)
			(end 0.67945 -0.3048)
			(stroke
				(width 0.1)
				(type default)
			)
			(layer "F.Fab")
		)
		(fp_line
			(start 0.67945 -0.3048)
			(end 0.67945 0.3048)
			(stroke
				(width 0.1)
				(type default)
			)
			(layer "F.Fab")
		)
		(fp_line
			(start -0.67945 -0.305054)
			(end -0.12065 -0.305054)
			(stroke
				(width 0.1)
				(type default)
			)
			(layer "F.Fab")
		)
		(fp_line
			(start -0.12065 -0.305054)
			(end -0.12065 -0.2794)
			(stroke
				(width 0.1)
				(type default)
			)
			(layer "F.Fab")
		)
		(pad "1" smd circle
			(at -0.40005 0 270)
			(size 0 0)
			(layers "F.Cu" "F.Mask" "F.Paste")
			(net "P3V3_SSD8")
		)
		(pad "2" smd circle
			(at 0.40005 0 270)
			(size 0 0)
			(layers "F.Cu" "F.Mask" "F.Paste")
			(net "PWRGD_P3V3_SSD8")
		)
	)
	(footprint ""
		(layer "F.Cu")
		(at 98.975672 -119.477028 180)
		(property "Reference" "R880"
			(at 0 0 180)
			(layer "F.SilkS")
			(hide yes)
			(effects
				(font
					(size 1.27 1.27)
				)
			)
		)
		(property "Value" ""
			(at 0 0 180)
			(layer "F.Fab")
			(effects
				(font
					(size 1.27 1.27)
				)
			)
		)
		(duplicate_pad_numbers_are_jumpers no)
		(fp_line
			(start 0.7874 0.4064)
			(end -0.7874 0.4064)
			(stroke
				(width 0.1524)
				(type default)
			)
			(layer "F.SilkS")
		)
		(fp_line
			(start 0.7874 -0.4064)
			(end 0.7874 0.4064)
			(stroke
				(width 0.1524)
				(type default)
			)
			(layer "F.SilkS")
		)
		(fp_line
			(start -0.7874 0.4064)
			(end -0.7874 -0.4064)
			(stroke
				(width 0.1524)
				(type default)
			)
			(layer "F.SilkS")
		)
		(fp_line
			(start -0.7874 -0.4064)
			(end 0.7874 -0.4064)
			(stroke
				(width 0.1524)
				(type default)
			)
			(layer "F.SilkS")
		)
		(fp_line
			(start 0.67945 0.3048)
			(end 0.120396 0.3048)
			(stroke
				(width 0.1)
				(type default)
			)
			(layer "F.Fab")
		)
		(fp_line
			(start 0.67945 -0.3048)
			(end 0.67945 0.3048)
			(stroke
				(width 0.1)
				(type default)
			)
			(layer "F.Fab")
		)
		(fp_line
			(start 0.12065 -0.2794)
			(end 0.12065 -0.3048)
			(stroke
				(width 0.1)
				(type default)
			)
			(layer "F.Fab")
		)
		(fp_line
			(start 0.12065 -0.3048)
			(end 0.67945 -0.3048)
			(stroke
				(width 0.1)
				(type default)
			)
			(layer "F.Fab")
		)
		(fp_line
			(start 0.120396 0.3048)
			(end 0.120396 0.2794)
			(stroke
				(width 0.1)
				(type default)
			)
			(layer "F.Fab")
		)
		(fp_line
			(start 0.120396 0.2794)
			(end -0.12065 0.2794)
			(stroke
				(width 0.1)
				(type default)
			)
			(layer "F.Fab")
		)
		(fp_line
			(start -0.12065 0.3048)
			(end -0.67945 0.3048)
			(stroke
				(width 0.1)
				(type default)
			)
			(layer "F.Fab")
		)
		(fp_line
			(start -0.12065 0.2794)
			(end -0.12065 0.3048)
			(stroke
				(width 0.1)
				(type default)
			)
			(layer "F.Fab")
		)
		(fp_line
			(start -0.12065 -0.2794)
			(end 0.12065 -0.2794)
			(stroke
				(width 0.1)
				(type default)
			)
			(layer "F.Fab")
		)
		(fp_line
			(start -0.12065 -0.305054)
			(end -0.12065 -0.2794)
			(stroke
				(width 0.1)
				(type default)
			)
			(layer "F.Fab")
		)
		(fp_line
			(start -0.67945 0.3048)
			(end -0.67945 -0.305054)
			(stroke
				(width 0.1)
				(type default)
			)
			(layer "F.Fab")
		)
		(fp_line
			(start -0.67945 -0.305054)
			(end -0.12065 -0.305054)
			(stroke
				(width 0.1)
				(type default)
			)
			(layer "F.Fab")
		)
		(pad "1" smd circle
			(at -0.40005 0 180)
			(size 0 0)
			(layers "F.Cu" "F.Mask" "F.Paste")
			(net "P3V3_NIC1")
		)
		(pad "2" smd circle
			(at 0.40005 0 180)
			(size 0 0)
			(layers "F.Cu" "F.Mask" "F.Paste")
			(net "PWRGD_P3V3_NIC1")
		)
	)
	(footprint ""
		(layer "F.Cu")
		(at 335.534 -205.232 -90)
		(property "Reference" "R4121"
			(at 0 0 270)
			(layer "F.SilkS")
			(hide yes)
			(effects
				(font
					(size 1.27 1.27)
				)
			)
		)
		(property "Value" ""
			(at 0 0 270)
			(layer "F.Fab")
			(effects
				(font
					(size 1.27 1.27)
				)
			)
		)
		(duplicate_pad_numbers_are_jumpers no)
		(fp_line
			(start -0.7874 0.4064)
			(end -0.7874 -0.4064)
			(stroke
				(width 0.1524)
				(type default)
			)
			(layer "F.SilkS")
		)
		(fp_line
			(start 0.7874 0.4064)
			(end -0.7874 0.4064)
			(stroke
				(width 0.1524)
				(type default)
			)
			(layer "F.SilkS")
		)
		(fp_line
			(start -0.7874 -0.4064)
			(end 0.7874 -0.4064)
			(stroke
				(width 0.1524)
				(type default)
			)
			(layer "F.SilkS")
		)
		(fp_line
			(start 0.7874 -0.4064)
			(end 0.7874 0.4064)
			(stroke
				(width 0.1524)
				(type default)
			)
			(layer "F.SilkS")
		)
		(fp_line
			(start -0.67945 0.3048)
			(end -0.67945 -0.305054)
			(stroke
				(width 0.1)
				(type default)
			)
			(layer "F.Fab")
		)
		(fp_line
			(start -0.12065 0.3048)
			(end -0.67945 0.3048)
			(stroke
				(width 0.1)
				(type default)
			)
			(layer "F.Fab")
		)
		(fp_line
			(start 0.120396 0.3048)
			(end 0.120396 0.2794)
			(stroke
				(width 0.1)
				(type default)
			)
			(layer "F.Fab")
		)
		(fp_line
			(start 0.67945 0.3048)
			(end 0.120396 0.3048)
			(stroke
				(width 0.1)
				(type default)
			)
			(layer "F.Fab")
		)
		(fp_line
			(start -0.12065 0.2794)
			(end -0.12065 0.3048)
			(stroke
				(width 0.1)
				(type default)
			)
			(layer "F.Fab")
		)
		(fp_line
			(start 0.120396 0.2794)
			(end -0.12065 0.2794)
			(stroke
				(width 0.1)
				(type default)
			)
			(layer "F.Fab")
		)
		(fp_line
			(start -0.12065 -0.2794)
			(end 0.12065 -0.2794)
			(stroke
				(width 0.1)
				(type default)
			)
			(layer "F.Fab")
		)
		(fp_line
			(start 0.12065 -0.2794)
			(end 0.12065 -0.3048)
			(stroke
				(width 0.1)
				(type default)
			)
			(layer "F.Fab")
		)
		(fp_line
			(start 0.12065 -0.3048)
			(end 0.67945 -0.3048)
			(stroke
				(width 0.1)
				(type default)
			)
			(layer "F.Fab")
		)
		(fp_line
			(start 0.67945 -0.3048)
			(end 0.67945 0.3048)
			(stroke
				(width 0.1)
				(type default)
			)
			(layer "F.Fab")
		)
		(fp_line
			(start -0.67945 -0.305054)
			(end -0.12065 -0.305054)
			(stroke
				(width 0.1)
				(type default)
			)
			(layer "F.Fab")
		)
		(fp_line
			(start -0.12065 -0.305054)
			(end -0.12065 -0.2794)
			(stroke
				(width 0.1)
				(type default)
			)
			(layer "F.Fab")
		)
		(pad "1" smd circle
			(at -0.40005 0 270)
			(size 0 0)
			(layers "F.Cu" "F.Mask" "F.Paste")
			(net "RST_SSD9_PERST_N")
		)
		(pad "2" smd circle
			(at 0.40005 0 270)
			(size 0 0)
			(layers "F.Cu" "F.Mask" "F.Paste")
			(net "RST_SSD9_PERST_R_N")
		)
	)
)
